(kicad_pcb
	(version 20260206)
	(generator "pcbnew")
	(generator_version "10.0")
	(general
		(thickness 1.6)
		(legacy_teardrops no)
	)
	(paper "A4")
	(title_block
		(title "baseboard — 13948-1b.1110WZS1818.brd")
		(comment 1 "Honey Badger (Wiwynn) / footprints 2158-2164 of 2523")
	)
	(layers
		(0 "F.Cu" signal "TOP")
		(4 "In1.Cu" signal "L2GND")
		(6 "In2.Cu" signal "L3")
		(8 "In3.Cu" signal "L4VCC")
		(10 "In4.Cu" signal "L5VCC")
		(12 "In5.Cu" signal "L6")
		(14 "In6.Cu" signal "L7GND")
		(2 "B.Cu" signal "BOTTOM")
		(9 "F.Adhes" user "F.Adhesive")
		(11 "B.Adhes" user "B.Adhesive")
		(13 "F.Paste" user "Package Geometry/Pastemask Top")
		(15 "B.Paste" user "Package Geometry/Pastemask Bottom")
		(5 "F.SilkS" user "Ref Des/Silkscreen Top")
		(7 "B.SilkS" user "Ref Des/Silkscreen Bottom")
		(1 "F.Mask" user "Board Geometry/Soldermask Top")
		(3 "B.Mask" user "Board Geometry/Soldermask Bottom")
		(17 "Dwgs.User" user "User.Drawings")
		(19 "Cmts.User" user "User.Comments")
		(21 "Eco1.User" user "User.Eco1")
		(23 "Eco2.User" user "User.Eco2")
		(25 "Edge.Cuts" user "Board Geometry/Outline")
		(27 "Margin" user)
		(31 "F.CrtYd" user "Package Geometry/Place Bound Top")
		(29 "B.CrtYd" user "Package Geometry/Place Bound Bottom")
		(35 "F.Fab" user "Ref Des/Assembly Top")
		(33 "B.Fab" user "Ref Des/Assembly Bottom")
	)
	(footprint ""
		(layer "B.Cu")
		(at 135.89 -35.179 180)
		(property "Reference" "SQ4"
			(at 0 0 0)
			(layer "B.SilkS")
			(hide yes)
			(effects
				(font
					(size 1.27 1.27)
				)
				(justify mirror)
			)
		)
		(property "Value" "2N7002A-7-GP"
			(at -0.127 -8.9662 180)
			(unlocked yes)
			(layer "B.Fab")
			(hide yes)
			(effects
				(font
					(size 1.016 1.016)
					(thickness 0.1524)
				)
				(justify mirror)
			)
		)
		(property "Device Type" "SOT23DGS2D4H48"
			(at -0.127 -10.4902 180)
			(unlocked yes)
			(layer "B.Fab")
			(hide yes)
			(effects
				(font
					(size 1.016 1.016)
					(thickness 0.1524)
				)
				(justify mirror)
			)
		)
		(duplicate_pad_numbers_are_jumpers no)
		(fp_line
			(start 1.651 1.778)
			(end -1.651 1.778)
			(stroke
				(width 0.1524)
				(type default)
			)
			(layer "B.SilkS")
		)
		(fp_line
			(start 1.651 -1.778)
			(end 1.651 1.778)
			(stroke
				(width 0.1524)
				(type default)
			)
			(layer "B.SilkS")
		)
		(fp_line
			(start -1.651 1.778)
			(end -1.651 -1.778)
			(stroke
				(width 0.1524)
				(type default)
			)
			(layer "B.SilkS")
		)
		(fp_line
			(start -1.651 -1.778)
			(end 1.651 -1.778)
			(stroke
				(width 0.1524)
				(type default)
			)
			(layer "B.SilkS")
		)
		(fp_poly
			(pts
				(xy 1.778 1.8796) (xy 1.778 -1.8796) (xy -1.778 -1.8796) (xy -1.778 1.8796)
			)
			(stroke
				(width 0)
				(type default)
			)
			(fill no)
			(layer "B.CrtYd")
		)
		(fp_poly
			(pts
				(xy 1.778 1.8796) (xy 1.778 -1.8796) (xy -1.778 -1.8796) (xy -1.778 1.8796)
			)
			(stroke
				(width 0)
				(type default)
			)
			(fill no)
			(layer "B.Fab")
		)
		(pad "D" smd custom
			(at 0 -0.9525)
			(size 0.1905 0.1905)
			(layers "B.Cu" "B.Mask" "B.Paste")
			(net "P3V3_STBY_R")
			(options
				(clearance outline)
				(anchor circle)
			)
			(primitives
				(gr_poly
					(pts
						(arc
							(start -0.1778 -0.5715)
							(mid -0.321484 -0.511984)
							(end -0.381 -0.3683)
						)
						(arc
							(start -0.381 0.3683)
							(mid -0.321484 0.511984)
							(end -0.1778 0.5715)
						)
						(arc
							(start 0.1778 0.5715)
							(mid 0.321484 0.511984)
							(end 0.381 0.3683)
						)
						(arc
							(start 0.381 -0.3683)
							(mid 0.321484 -0.511984)
							(end 0.1778 -0.5715)
						)
					)
					(width 0)
					(fill yes)
				)
			)
		)
		(pad "G" smd custom
			(at 0.98425 0.9525)
			(size 0.1905 0.1905)
			(layers "B.Cu" "B.Mask" "B.Paste")
			(net "PMU_PLTRST_R_N")
			(options
				(clearance outline)
				(anchor circle)
			)
			(primitives
				(gr_poly
					(pts
						(arc
							(start -0.1778 -0.5715)
							(mid -0.321484 -0.511984)
							(end -0.381 -0.3683)
						)
						(arc
							(start -0.381 0.3683)
							(mid -0.321484 0.511984)
							(end -0.1778 0.5715)
						)
						(arc
							(start 0.1778 0.5715)
							(mid 0.321484 0.511984)
							(end 0.381 0.3683)
						)
						(arc
							(start 0.381 -0.3683)
							(mid 0.321484 -0.511984)
							(end 0.1778 -0.5715)
						)
					)
					(width 0)
					(fill yes)
				)
			)
		)
		(pad "S" smd custom
			(at -0.98425 0.9525)
			(size 0.1905 0.1905)
			(layers "B.Cu" "B.Mask" "B.Paste")
			(net "GND")
			(options
				(clearance outline)
				(anchor circle)
			)
			(primitives
				(gr_poly
					(pts
						(arc
							(start -0.1778 -0.5715)
							(mid -0.321484 -0.511984)
							(end -0.381 -0.3683)
						)
						(arc
							(start -0.381 0.3683)
							(mid -0.321484 0.511984)
							(end -0.1778 0.5715)
						)
						(arc
							(start 0.1778 0.5715)
							(mid 0.321484 0.511984)
							(end 0.381 0.3683)
						)
						(arc
							(start 0.381 -0.3683)
							(mid 0.321484 -0.511984)
							(end 0.1778 -0.5715)
						)
					)
					(width 0)
					(fill yes)
				)
			)
		)
	)
	(footprint ""
		(layer "B.Cu")
		(at 173.863 -113.284 90)
		(property "Reference" "PR153"
			(at 0 0 90)
			(layer "B.SilkS")
			(hide yes)
			(effects
				(font
					(size 1.27 1.27)
				)
				(justify mirror)
			)
		)
		(property "Value" "0R5J-5-GP"
			(at 0 -8.9535 90)
			(unlocked yes)
			(layer "B.Fab")
			(hide yes)
			(effects
				(font
					(size 1.27 1.016)
					(thickness 0.1524)
				)
				(justify mirror)
			)
		)
		(property "Device Type" "R805H24"
			(at 0 -10.6299 90)
			(unlocked yes)
			(layer "B.Fab")
			(hide yes)
			(effects
				(font
					(size 1.27 1.016)
					(thickness 0.1524)
				)
				(justify mirror)
			)
		)
		(duplicate_pad_numbers_are_jumpers no)
		(fp_line
			(start 0.889 -1.7018)
			(end 0.889 0.2794)
			(stroke
				(width 0.1524)
				(type default)
			)
			(layer "B.SilkS")
		)
		(fp_line
			(start -0.889 -1.7018)
			(end 0.889 -1.7018)
			(stroke
				(width 0.1524)
				(type default)
			)
			(layer "B.SilkS")
		)
		(fp_line
			(start -0.889 -1.7018)
			(end -0.889 -0.381)
			(stroke
				(width 0.1524)
				(type default)
			)
			(layer "B.SilkS")
		)
		(fp_line
			(start 0.889 0.0762)
			(end 0.889 1.7018)
			(stroke
				(width 0.1524)
				(type default)
			)
			(layer "B.SilkS")
		)
		(fp_line
			(start 0.889 1.7018)
			(end -0.889 1.7018)
			(stroke
				(width 0.1524)
				(type default)
			)
			(layer "B.SilkS")
		)
		(fp_line
			(start -0.889 1.7018)
			(end -0.889 -0.508)
			(stroke
				(width 0.1524)
				(type default)
			)
			(layer "B.SilkS")
		)
		(fp_poly
			(pts
				(xy -0.9652 -1.778) (xy -0.9652 1.778) (xy 0.9652 1.778) (xy 0.9652 -1.778)
			)
			(stroke
				(width 0)
				(type default)
			)
			(fill no)
			(layer "B.CrtYd")
		)
		(fp_rect
			(start 0.9652 1.778)
			(end -0.9652 -1.778)
			(stroke
				(width 0)
				(type default)
			)
			(fill no)
			(layer "B.Fab")
		)
		(pad "1" smd rect
			(at 0 -0.9652 270)
			(size 1.397 1.143)
			(layers "B.Cu" "B.Mask" "B.Paste")
			(net "P0V9_E_VBST_RC")
		)
		(pad "2" smd rect
			(at 0 0.9652 270)
			(size 1.397 1.143)
			(layers "B.Cu" "B.Mask" "B.Paste")
			(net "P0V9_E_LX")
		)
	)
	(footprint ""
		(layer "B.Cu")
		(at 101.61016 -31.640018)
		(property "Reference" "SC872"
			(at 0 0 0)
			(layer "B.SilkS")
			(hide yes)
			(effects
				(font
					(size 1.27 1.27)
				)
				(justify mirror)
			)
		)
		(property "Value" "SCD22U6D3V1MX-1-GP"
			(at 2.8321 -1.7399 0)
			(unlocked yes)
			(layer "B.Fab")
			(hide yes)
			(effects
				(font
					(size 1.016 1.016)
					(thickness 0.1524)
				)
				(justify mirror)
			)
		)
		(property "Device Type" "C0201H13"
			(at 2.8321 -3.2639 0)
			(unlocked yes)
			(layer "B.Fab")
			(hide yes)
			(effects
				(font
					(size 1.016 1.016)
					(thickness 0.1524)
				)
				(justify mirror)
			)
		)
		(duplicate_pad_numbers_are_jumpers no)
		(fp_rect
			(start 0.2794 0.6477)
			(end -0.2794 -0.6477)
			(stroke
				(width 0)
				(type default)
			)
			(fill no)
			(layer "B.CrtYd")
		)
		(fp_rect
			(start 0.2794 0.6477)
			(end -0.2794 -0.6477)
			(stroke
				(width 0)
				(type default)
			)
			(fill no)
			(layer "B.Fab")
		)
		(pad "1" smd custom
			(at 0 -0.2794 180)
			(size 0.0762 0.0762)
			(layers "B.Cu" "B.Mask" "B.Paste")
			(net "PCIE_SAS_C_CPU_RX_N5")
			(options
				(clearance outline)
				(anchor circle)
			)
			(primitives
				(gr_poly
					(pts
						(arc
							(start 0.1524 0.127)
							(mid 0.137521 0.162921)
							(end 0.1016 0.1778)
						)
						(arc
							(start -0.1016 0.1778)
							(mid -0.137521 0.162921)
							(end -0.1524 0.127)
						)
						(arc
							(start -0.1524 -0.127)
							(mid -0.137521 -0.162921)
							(end -0.1016 -0.1778)
						)
						(arc
							(start 0.1016 -0.1778)
							(mid 0.137521 -0.162921)
							(end 0.1524 -0.127)
						)
					)
					(width 0)
					(fill yes)
				)
			)
		)
		(pad "2" smd custom
			(at 0 0.2794 180)
			(size 0.0762 0.0762)
			(layers "B.Cu" "B.Mask" "B.Paste")
			(net "PCIE_SAS_CPU_RX_N5")
			(options
				(clearance outline)
				(anchor circle)
			)
			(primitives
				(gr_poly
					(pts
						(arc
							(start 0.1524 0.127)
							(mid 0.137521 0.162921)
							(end 0.1016 0.1778)
						)
						(arc
							(start -0.1016 0.1778)
							(mid -0.137521 0.162921)
							(end -0.1524 0.127)
						)
						(arc
							(start -0.1524 -0.127)
							(mid -0.137521 -0.162921)
							(end -0.1016 -0.1778)
						)
						(arc
							(start 0.1016 -0.1778)
							(mid 0.137521 -0.162921)
							(end 0.1524 -0.127)
						)
					)
					(width 0)
					(fill yes)
				)
			)
		)
	)
	(footprint ""
		(layer "B.Cu")
		(at 101.48697 -108.204)
		(property "Reference" "TP262"
			(at 0 0 0)
			(layer "B.SilkS")
			(hide yes)
			(effects
				(font
					(size 1.27 1.27)
				)
				(justify mirror)
			)
		)
		(property "Value" "TPAD28"
			(at -0.0127 -1.8034 0)
			(unlocked yes)
			(layer "B.Fab")
			(hide yes)
			(effects
				(font
					(size 1.016 1.016)
					(thickness 0.1524)
				)
				(justify mirror)
			)
		)
		(property "Device Type" "TPAD28"
			(at -0.0127 -3.3274 0)
			(unlocked yes)
			(layer "B.Fab")
			(hide yes)
			(effects
				(font
					(size 1.016 1.016)
					(thickness 0.1524)
				)
				(justify mirror)
			)
		)
		(duplicate_pad_numbers_are_jumpers no)
		(fp_poly
			(pts
				(arc
					(start 0.3556 0)
					(mid -0.3556 0)
					(end 0.3556 0)
				)
			)
			(stroke
				(width 0)
				(type default)
			)
			(fill no)
			(layer "B.CrtYd")
		)
		(fp_poly
			(pts
				(arc
					(start 0.6096 0)
					(mid -0.6096 0)
					(end 0.6096 0)
				)
			)
			(stroke
				(width 0)
				(type default)
			)
			(fill no)
			(layer "B.Fab")
		)
		(pad "1" smd circle
			(at 0 0 180)
			(size 0.7112 0.7112)
			(layers "B.Cu" "B.Mask" "B.Paste")
			(net "EXP_SIO_CLK_OUT")
		)
	)
	(footprint ""
		(layer "B.Cu")
		(at 106.353356 -40.3479)
		(property "Reference" "SC1041"
			(at 0 0 0)
			(layer "B.SilkS")
			(hide yes)
			(effects
				(font
					(size 1.27 1.27)
				)
				(justify mirror)
			)
		)
		(property "Value" "SCD1U16V2KX-3GP"
			(at -1.1811 -2.7051 0)
			(unlocked yes)
			(layer "B.Fab")
			(hide yes)
			(effects
				(font
					(size 1.016 1.016)
					(thickness 0.1524)
				)
				(justify mirror)
			)
		)
		(property "Device Type" "C402H22"
			(at -1.1811 -4.2291 0)
			(unlocked yes)
			(layer "B.Fab")
			(hide yes)
			(effects
				(font
					(size 1.016 1.016)
					(thickness 0.1524)
				)
				(justify mirror)
			)
		)
		(duplicate_pad_numbers_are_jumpers no)
		(fp_rect
			(start 0.4318 0.9525)
			(end -0.4318 -0.9525)
			(stroke
				(width 0)
				(type default)
			)
			(fill no)
			(layer "B.CrtYd")
		)
		(fp_rect
			(start 0.4318 0.9525)
			(end -0.4318 -0.9525)
			(stroke
				(width 0)
				(type default)
			)
			(fill no)
			(layer "B.Fab")
		)
		(pad "1" smd custom
			(at 0 -0.4445 180)
			(size 0.1524 0.1524)
			(layers "B.Cu" "B.Mask" "B.Paste")
			(net "P0V955_C")
			(options
				(clearance outline)
				(anchor circle)
			)
			(primitives
				(gr_poly
					(pts
						(arc
							(start 0.3048 0.2032)
							(mid 0.275042 0.275042)
							(end 0.2032 0.3048)
						)
						(arc
							(start -0.2032 0.3048)
							(mid -0.275042 0.275042)
							(end -0.3048 0.2032)
						)
						(arc
							(start -0.3048 -0.2032)
							(mid -0.275042 -0.275042)
							(end -0.2032 -0.3048)
						)
						(arc
							(start 0.2032 -0.3048)
							(mid 0.275042 -0.275042)
							(end 0.3048 -0.2032)
						)
					)
					(width 0)
					(fill yes)
				)
			)
		)
		(pad "2" smd custom
			(at 0 0.4445 180)
			(size 0.1524 0.1524)
			(layers "B.Cu" "B.Mask" "B.Paste")
			(net "GND")
			(options
				(clearance outline)
				(anchor circle)
			)
			(primitives
				(gr_poly
					(pts
						(arc
							(start 0.3048 0.2032)
							(mid 0.275042 0.275042)
							(end 0.2032 0.3048)
						)
						(arc
							(start -0.2032 0.3048)
							(mid -0.275042 0.275042)
							(end -0.3048 0.2032)
						)
						(arc
							(start -0.3048 -0.2032)
							(mid -0.275042 -0.275042)
							(end -0.2032 -0.3048)
						)
						(arc
							(start 0.2032 -0.3048)
							(mid 0.275042 -0.275042)
							(end 0.3048 -0.2032)
						)
					)
					(width 0)
					(fill yes)
				)
			)
		)
	)
	(footprint ""
		(layer "B.Cu")
		(at 121.412 -47.302674 90)
		(property "Reference" "SR583"
			(at 0 0 90)
			(layer "B.SilkS")
			(hide yes)
			(effects
				(font
					(size 1.27 1.27)
				)
				(justify mirror)
			)
		)
		(property "Value" "10KR2F-2-GP"
			(at -0.064008 -3.993896 90)
			(unlocked yes)
			(layer "B.Fab")
			(hide yes)
			(effects
				(font
					(size 1.016 1.016)
					(thickness 0.1524)
				)
				(justify mirror)
			)
		)
		(property "Device Type" "R402H16"
			(at -0.064008 -5.517896 90)
			(unlocked yes)
			(layer "B.Fab")
			(hide yes)
			(effects
				(font
					(size 1.016 1.016)
					(thickness 0.1524)
				)
				(justify mirror)
			)
		)
		(duplicate_pad_numbers_are_jumpers no)
		(fp_line
			(start 0.508 -0.9398)
			(end 0.508 0.9398)
			(stroke
				(width 0.1524)
				(type default)
			)
			(layer "B.SilkS")
		)
		(fp_line
			(start -0.508 -0.9398)
			(end 0.508 -0.9398)
			(stroke
				(width 0.1524)
				(type default)
			)
			(layer "B.SilkS")
		)
		(fp_rect
			(start 0.508 0.9398)
			(end -0.508 -0.9398)
			(stroke
				(width 0)
				(type default)
			)
			(fill no)
			(layer "B.CrtYd")
		)
		(fp_rect
			(start 0.508 0.9398)
			(end -0.508 -0.9398)
			(stroke
				(width 0)
				(type default)
			)
			(fill no)
			(layer "B.Fab")
		)
		(pad "1" smd custom
			(at 0 -0.4445 270)
			(size 0.1397 0.1397)
			(layers "B.Cu" "B.Mask" "B.Paste")
			(net "IOC_CLK_SEL0")
			(options
				(clearance outline)
				(anchor circle)
			)
			(primitives
				(gr_poly
					(pts
						(arc
							(start -0.1778 0.2794)
							(mid -0.249642 0.249642)
							(end -0.2794 0.1778)
						)
						(arc
							(start -0.2794 -0.1778)
							(mid -0.249642 -0.249642)
							(end -0.1778 -0.2794)
						)
						(arc
							(start 0.1778 -0.2794)
							(mid 0.249642 -0.249642)
							(end 0.2794 -0.1778)
						)
						(arc
							(start 0.2794 0.1778)
							(mid 0.249642 0.249642)
							(end 0.1778 0.2794)
						)
					)
					(width 0)
					(fill yes)
				)
			)
		)
		(pad "2" smd custom
			(at 0 0.4445 270)
			(size 0.1397 0.1397)
			(layers "B.Cu" "B.Mask" "B.Paste")
			(net "P1V8_C")
			(options
				(clearance outline)
				(anchor circle)
			)
			(primitives
				(gr_poly
					(pts
						(arc
							(start -0.1778 0.2794)
							(mid -0.249642 0.249642)
							(end -0.2794 0.1778)
						)
						(arc
							(start -0.2794 -0.1778)
							(mid -0.249642 -0.249642)
							(end -0.1778 -0.2794)
						)
						(arc
							(start 0.1778 -0.2794)
							(mid 0.249642 -0.249642)
							(end 0.2794 -0.1778)
						)
						(arc
							(start 0.2794 0.1778)
							(mid 0.249642 0.249642)
							(end 0.1778 0.2794)
						)
					)
					(width 0)
					(fill yes)
				)
			)
		)
	)
	(footprint ""
		(layer "B.Cu")
		(at 271.907 -35.687 90)
		(property "Reference" "PC47"
			(at 0 0 90)
			(layer "B.SilkS")
			(hide yes)
			(effects
				(font
					(size 1.27 1.27)
				)
				(justify mirror)
			)
		)
		(property "Value" "SCD1U50V3KX-GP"
			(at 0 -2.8194 90)
			(unlocked yes)
			(layer "B.Fab")
			(hide yes)
			(effects
				(font
					(size 1.016 1.016)
					(thickness 0.1524)
				)
				(justify mirror)
			)
		)
		(property "Device Type" "C603H36"
			(at 0 -4.3434 90)
			(unlocked yes)
			(layer "B.Fab")
			(hide yes)
			(effects
				(font
					(size 1.016 1.016)
					(thickness 0.1524)
				)
				(justify mirror)
			)
		)
		(duplicate_pad_numbers_are_jumpers no)
		(fp_line
			(start -0.508 0)
			(end 0.508 0)
			(stroke
				(width 0.2032)
				(type default)
			)
			(layer "B.SilkS")
		)
		(fp_rect
			(start 0.5842 1.3335)
			(end -0.5842 -1.3335)
			(stroke
				(width 0)
				(type default)
			)
			(fill no)
			(layer "B.CrtYd")
		)
		(fp_rect
			(start 0.5842 1.3335)
			(end -0.5842 -1.3335)
			(stroke
				(width 0)
				(type default)
			)
			(fill no)
			(layer "B.Fab")
		)
		(pad "1" smd custom
			(at 0 -0.762 270)
			(size 0.2159 0.2159)
			(layers "B.Cu" "B.Mask" "B.Paste")
			(net "P1V8_STBY_VBST_RC")
			(options
				(clearance outline)
				(anchor circle)
			)
			(primitives
				(gr_poly
					(pts
						(arc
							(start -0.3302 0.4318)
							(mid -0.402042 0.402042)
							(end -0.4318 0.3302)
						)
						(arc
							(start -0.4318 -0.3302)
							(mid -0.402042 -0.402042)
							(end -0.3302 -0.4318)
						)
						(arc
							(start 0.3302 -0.4318)
							(mid 0.402042 -0.402042)
							(end 0.4318 -0.3302)
						)
						(arc
							(start 0.4318 0.3302)
							(mid 0.402042 0.402042)
							(end 0.3302 0.4318)
						)
					)
					(width 0)
					(fill yes)
				)
			)
		)
		(pad "2" smd custom
			(at 0 0.762 270)
			(size 0.2159 0.2159)
			(layers "B.Cu" "B.Mask" "B.Paste")
			(net "P1V8_STBY_LL")
			(options
				(clearance outline)
				(anchor circle)
			)
			(primitives
				(gr_poly
					(pts
						(arc
							(start -0.3302 0.4318)
							(mid -0.402042 0.402042)
							(end -0.4318 0.3302)
						)
						(arc
							(start -0.4318 -0.3302)
							(mid -0.402042 -0.402042)
							(end -0.3302 -0.4318)
						)
						(arc
							(start 0.3302 -0.4318)
							(mid 0.402042 -0.402042)
							(end 0.4318 -0.3302)
						)
						(arc
							(start 0.4318 0.3302)
							(mid 0.402042 0.402042)
							(end 0.3302 0.4318)
						)
					)
					(width 0)
					(fill yes)
				)
			)
		)
	)
)
